(kicad_pcb
	(version 20260206)
	(generator "pcbnew")
	(generator_version "10.0")
	(general
		(thickness 1.6)
		(legacy_teardrops no)
	)
	(paper "A4")
	(title_block
		(title "Wiwynn_Tioga_Pass_MB.brd")
		(comment 1 "Tioga Pass / footprint 2254 of 4770 (U5D1), pads 729-806 of 3647")
	)
	(layers
		(0 "F.Cu" signal "TOP")
		(4 "In1.Cu" signal "L2GND")
		(6 "In2.Cu" signal "L3")
		(8 "In3.Cu" signal "L4GND")
		(10 "In4.Cu" signal "L5")
		(12 "In5.Cu" signal "L6GND")
		(14 "In6.Cu" signal "L7VCC")
		(16 "In7.Cu" signal "L8VCC")
		(18 "In8.Cu" signal "L9GND")
		(20 "In9.Cu" signal "L10")
		(22 "In10.Cu" signal "L11GND")
		(24 "In11.Cu" signal "L12")
		(26 "In12.Cu" signal "L13GND")
		(2 "B.Cu" signal "BOTTOM")
		(9 "F.Adhes" user "F.Adhesive")
		(11 "B.Adhes" user "B.Adhesive")
		(13 "F.Paste" user "Package Geometry/Pastemask Top")
		(15 "B.Paste" user "Package Geometry/Pastemask Bottom")
		(5 "F.SilkS" user "Ref Des/Silkscreen Top")
		(7 "B.SilkS" user "Ref Des/Silkscreen Bottom")
		(1 "F.Mask" user "Board Geometry/Soldermask Top")
		(3 "B.Mask" user "Board Geometry/Soldermask Bottom")
		(17 "Dwgs.User" user "User.Drawings")
		(19 "Cmts.User" user "User.Comments")
		(21 "Eco1.User" user "User.Eco1")
		(23 "Eco2.User" user "User.Eco2")
		(25 "Edge.Cuts" user "Board Geometry/Outline")
		(27 "Margin" user)
		(31 "F.CrtYd" user "Package Geometry/Place Bound Top")
		(29 "B.CrtYd" user "Package Geometry/Place Bound Bottom")
		(35 "F.Fab" user "Ref Des/Assembly Top")
		(33 "B.Fab" user "Ref Des/Assembly Bottom")
	)
	(footprint ""
		(layer "F.Cu")
		(at 270.000222 -76.550012 180)
		(property "Reference" "U5D1"
			(at 19.124422 31.601918 0)
			(unlocked yes)
			(layer "F.SilkS")
			(effects
				(font
					(size 0.7874 0.5842)
					(thickness 0.1524)
				)
			)
		)
		(property "Value" ""
			(at 0 0 180)
			(layer "F.Fab")
			(effects
				(font
					(size 1.27 1.27)
				)
			)
		)
		(duplicate_pad_numbers_are_jumpers no)
		(pad "B11" smd circle
			(at -28.665424 -24.608028)
			(size 0.4318 0.4318)
			(layers "F.Cu" "F.Mask" "F.Paste")
			(net "PVPP_ABC")
		)
		(pad "B13" smd circle
			(at -26.948384 -24.608028)
			(size 0.4318 0.4318)
			(layers "F.Cu" "F.Mask" "F.Paste")
			(net "P1V8_MCP_CPU0")
		)
		(pad "B15" smd circle
			(at -25.231598 -24.608028)
			(size 0.4318 0.4318)
			(layers "F.Cu" "F.Mask" "F.Paste")
			(net "P1V8_MCP_CPU0")
		)
		(pad "B17" smd custom
			(at -23.514558 -24.608028)
			(size 0.10795 0.10795)
			(layers "F.Cu" "F.Mask" "F.Paste")
			(net "P1V8_MCP_CPU0")
			(options
				(clearance outline)
				(anchor circle)
			)
			(primitives
				(gr_poly
					(pts
						(arc
							(start 0.2159 -0.0381)
							(mid 0 -0.254)
							(end -0.2159 -0.0381)
						)
						(arc
							(start -0.2159 0.0381)
							(mid 0 0.254)
							(end 0.2159 0.0381)
						)
					)
					(width 0)
					(fill yes)
				)
			)
		)
		(pad "B25" smd circle
			(at -16.646398 -24.608028)
			(size 0.4318 0.4318)
			(layers "F.Cu" "F.Mask" "F.Paste")
			(net "GND")
		)
		(pad "B27" smd circle
			(at -14.929612 -24.608028)
			(size 0.4318 0.4318)
			(layers "F.Cu" "F.Mask" "F.Paste")
			(net "M_B_DQ<54>")
		)
		(pad "B29" smd circle
			(at -13.212572 -24.608028)
			(size 0.4318 0.4318)
			(layers "F.Cu" "F.Mask" "F.Paste")
			(net "M_B_DQ<49>")
		)
		(pad "B31" smd circle
			(at -11.495532 -24.608028)
			(size 0.4318 0.4318)
			(layers "F.Cu" "F.Mask" "F.Paste")
			(net "GND")
		)
		(pad "B33" smd circle
			(at -9.778492 -24.608028)
			(size 0.4318 0.4318)
			(layers "F.Cu" "F.Mask" "F.Paste")
			(net "M_B_DQ<46>")
		)
		(pad "B35" smd circle
			(at -8.061452 -24.608028)
			(size 0.4318 0.4318)
			(layers "F.Cu" "F.Mask" "F.Paste")
			(net "M_B_DQ<41>")
		)
		(pad "B37" smd circle
			(at -6.344412 -24.608028)
			(size 0.4318 0.4318)
			(layers "F.Cu" "F.Mask" "F.Paste")
			(net "GND")
		)
		(pad "B39" smd circle
			(at -4.627626 -24.608028)
			(size 0.4318 0.4318)
			(layers "F.Cu" "F.Mask" "F.Paste")
			(net "M_A_DQ<38>")
		)
		(pad "B41" smd circle
			(at -2.910586 -24.608028)
			(size 0.4318 0.4318)
			(layers "F.Cu" "F.Mask" "F.Paste")
			(net "M_A_DQ<33>")
		)
		(pad "B43" smd custom
			(at -1.193546 -24.608028 315)
			(size 0.10795 0.10795)
			(layers "F.Cu" "F.Mask" "F.Paste")
			(net "GND")
			(options
				(clearance outline)
				(anchor circle)
			)
			(primitives
				(gr_poly
					(pts
						(arc
							(start 0.2159 -0.0381)
							(mid 0 -0.254)
							(end -0.2159 -0.0381)
						)
						(arc
							(start -0.2159 0.0381)
							(mid 0 0.254)
							(end 0.2159 0.0381)
						)
					)
					(width 0)
					(fill yes)
				)
			)
		)
		(pad "B47" smd custom
			(at 3.769106 -26.408126 45)
			(size 0.10795 0.10795)
			(layers "F.Cu" "F.Mask" "F.Paste")
			(net "PVDDQ_ABC")
			(options
				(clearance outline)
				(anchor circle)
			)
			(primitives
				(gr_poly
					(pts
						(arc
							(start 0.2159 -0.0381)
							(mid 0 -0.254)
							(end -0.2159 -0.0381)
						)
						(arc
							(start -0.2159 0.0381)
							(mid 0 0.254)
							(end 0.2159 0.0381)
						)
					)
					(width 0)
					(fill yes)
				)
			)
		)
		(pad "B49" smd custom
			(at 5.485892 -26.408126)
			(size 0.10795 0.10795)
			(layers "F.Cu" "F.Mask" "F.Paste")
			(net "PVDDQ_ABC")
			(options
				(clearance outline)
				(anchor circle)
			)
			(primitives
				(gr_poly
					(pts
						(arc
							(start 0.2159 -0.0381)
							(mid 0 -0.254)
							(end -0.2159 -0.0381)
						)
						(arc
							(start -0.2159 0.0381)
							(mid 0 0.254)
							(end 0.2159 0.0381)
						)
					)
					(width 0)
					(fill yes)
				)
			)
		)
		(pad "B51" smd custom
			(at 7.202932 -26.408126)
			(size 0.10795 0.10795)
			(layers "F.Cu" "F.Mask" "F.Paste")
			(net "M_A_CS_N<4>")
			(options
				(clearance outline)
				(anchor circle)
			)
			(primitives
				(gr_poly
					(pts
						(arc
							(start 0.2159 -0.0381)
							(mid 0 -0.254)
							(end -0.2159 -0.0381)
						)
						(arc
							(start -0.2159 0.0381)
							(mid 0 0.254)
							(end 0.2159 0.0381)
						)
					)
					(width 0)
					(fill yes)
				)
			)
		)
		(pad "B53" smd custom
			(at 8.919972 -26.408126)
			(size 0.10795 0.10795)
			(layers "F.Cu" "F.Mask" "F.Paste")
			(net "PVDDQ_ABC")
			(options
				(clearance outline)
				(anchor circle)
			)
			(primitives
				(gr_poly
					(pts
						(arc
							(start 0.2159 -0.0381)
							(mid 0 -0.254)
							(end -0.2159 -0.0381)
						)
						(arc
							(start -0.2159 0.0381)
							(mid 0 0.254)
							(end 0.2159 0.0381)
						)
					)
					(width 0)
					(fill yes)
				)
			)
		)
		(pad "B55" smd custom
			(at 10.637012 -26.408126)
			(size 0.10795 0.10795)
			(layers "F.Cu" "F.Mask" "F.Paste")
			(net "M_A_CLK_DP<1>")
			(options
				(clearance outline)
				(anchor circle)
			)
			(primitives
				(gr_poly
					(pts
						(arc
							(start 0.2159 -0.0381)
							(mid 0 -0.254)
							(end -0.2159 -0.0381)
						)
						(arc
							(start -0.2159 0.0381)
							(mid 0 0.254)
							(end 0.2159 0.0381)
						)
					)
					(width 0)
					(fill yes)
				)
			)
		)
		(pad "B57" smd custom
			(at 12.354052 -26.408126)
			(size 0.10795 0.10795)
			(layers "F.Cu" "F.Mask" "F.Paste")
			(net "M_A_CLK_DP<3>")
			(options
				(clearance outline)
				(anchor circle)
			)
			(primitives
				(gr_poly
					(pts
						(arc
							(start 0.2159 -0.0381)
							(mid 0 -0.254)
							(end -0.2159 -0.0381)
						)
						(arc
							(start -0.2159 0.0381)
							(mid 0 0.254)
							(end 0.2159 0.0381)
						)
					)
					(width 0)
					(fill yes)
				)
			)
		)
		(pad "B59" smd custom
			(at 14.071092 -26.408126)
			(size 0.10795 0.10795)
			(layers "F.Cu" "F.Mask" "F.Paste")
			(net "PVDDQ_ABC")
			(options
				(clearance outline)
				(anchor circle)
			)
			(primitives
				(gr_poly
					(pts
						(arc
							(start 0.2159 -0.0381)
							(mid 0 -0.254)
							(end -0.2159 -0.0381)
						)
						(arc
							(start -0.2159 0.0381)
							(mid 0 0.254)
							(end 0.2159 0.0381)
						)
					)
					(width 0)
					(fill yes)
				)
			)
		)
		(pad "B61" smd custom
			(at 15.787878 -26.408126)
			(size 0.10795 0.10795)
			(layers "F.Cu" "F.Mask" "F.Paste")
			(net "M_A_ALERT_N")
			(options
				(clearance outline)
				(anchor circle)
			)
			(primitives
				(gr_poly
					(pts
						(arc
							(start 0.2159 -0.0381)
							(mid 0 -0.254)
							(end -0.2159 -0.0381)
						)
						(arc
							(start -0.2159 0.0381)
							(mid 0 0.254)
							(end 0.2159 0.0381)
						)
					)
					(width 0)
					(fill yes)
				)
			)
		)
		(pad "B63" smd custom
			(at 17.504918 -26.408126)
			(size 0.10795 0.10795)
			(layers "F.Cu" "F.Mask" "F.Paste")
			(net "M_A_CKE<2>")
			(options
				(clearance outline)
				(anchor circle)
			)
			(primitives
				(gr_poly
					(pts
						(arc
							(start 0.2159 -0.0381)
							(mid 0 -0.254)
							(end -0.2159 -0.0381)
						)
						(arc
							(start -0.2159 0.0381)
							(mid 0 0.254)
							(end 0.2159 0.0381)
						)
					)
					(width 0)
					(fill yes)
				)
			)
		)
		(pad "B71" smd custom
			(at 24.373078 -26.408126)
			(size 0.10795 0.10795)
			(layers "F.Cu" "F.Mask" "F.Paste")
			(net "GND")
			(options
				(clearance outline)
				(anchor circle)
			)
			(primitives
				(gr_poly
					(pts
						(arc
							(start 0.2159 -0.0381)
							(mid 0 -0.254)
							(end -0.2159 -0.0381)
						)
						(arc
							(start -0.2159 0.0381)
							(mid 0 0.254)
							(end 0.2159 0.0381)
						)
					)
					(width 0)
					(fill yes)
				)
			)
		)
		(pad "B73" smd custom
			(at 26.090118 -26.408126)
			(size 0.10795 0.10795)
			(layers "F.Cu" "F.Mask" "F.Paste")
			(net "M_B_DQS_DN<12>")
			(options
				(clearance outline)
				(anchor circle)
			)
			(primitives
				(gr_poly
					(pts
						(arc
							(start 0.2159 -0.0381)
							(mid 0 -0.254)
							(end -0.2159 -0.0381)
						)
						(arc
							(start -0.2159 0.0381)
							(mid 0 0.254)
							(end 0.2159 0.0381)
						)
					)
					(width 0)
					(fill yes)
				)
			)
		)
		(pad "B75" smd custom
			(at 27.806904 -26.408126)
			(size 0.10795 0.10795)
			(layers "F.Cu" "F.Mask" "F.Paste")
			(net "GND")
			(options
				(clearance outline)
				(anchor circle)
			)
			(primitives
				(gr_poly
					(pts
						(arc
							(start 0.2159 -0.0381)
							(mid 0 -0.254)
							(end -0.2159 -0.0381)
						)
						(arc
							(start -0.2159 0.0381)
							(mid 0 0.254)
							(end 0.2159 0.0381)
						)
					)
					(width 0)
					(fill yes)
				)
			)
		)
		(pad "B77" smd custom
			(at 29.523944 -26.408126)
			(size 0.10795 0.10795)
			(layers "F.Cu" "F.Mask" "F.Paste")
			(net "TP_CPU0_RSVD_293")
			(options
				(clearance outline)
				(anchor circle)
			)
			(primitives
				(gr_poly
					(pts
						(arc
							(start 0.2159 -0.0381)
							(mid 0 -0.254)
							(end -0.2159 -0.0381)
						)
						(arc
							(start -0.2159 0.0381)
							(mid 0 0.254)
							(end 0.2159 0.0381)
						)
					)
					(width 0)
					(fill yes)
				)
			)
		)
		(pad "B79" smd custom
			(at 31.240984 -26.408126 315)
			(size 0.10795 0.10795)
			(layers "F.Cu" "F.Mask" "F.Paste")
			(net "GND")
			(options
				(clearance outline)
				(anchor circle)
			)
			(primitives
				(gr_poly
					(pts
						(arc
							(start 0.2159 -0.0381)
							(mid 0 -0.254)
							(end -0.2159 -0.0381)
						)
						(arc
							(start -0.2159 0.0381)
							(mid 0 0.254)
							(end 0.2159 0.0381)
						)
					)
					(width 0)
					(fill yes)
				)
			)
		)
		(pad "B81" smd custom
			(at 32.958024 -26.408126 315)
			(size 0.10795 0.10795)
			(layers "F.Cu" "F.Mask" "F.Paste")
			(net "TP_CPU0_RSVD_292")
			(options
				(clearance outline)
				(anchor circle)
			)
			(primitives
				(gr_poly
					(pts
						(arc
							(start 0.2159 -0.0381)
							(mid 0 -0.254)
							(end -0.2159 -0.0381)
						)
						(arc
							(start -0.2159 0.0381)
							(mid 0 0.254)
							(end 0.2159 0.0381)
						)
					)
					(width 0)
					(fill yes)
				)
			)
		)
		(pad "BA2" smd custom
			(at -36.392104 -5.291074 90)
			(size 0.10795 0.10795)
			(layers "F.Cu" "F.Mask" "F.Paste")
			(net "GND")
			(options
				(clearance outline)
				(anchor circle)
			)
			(primitives
				(gr_poly
					(pts
						(arc
							(start 0.2159 -0.0381)
							(mid 0 -0.254)
							(end -0.2159 -0.0381)
						)
						(arc
							(start -0.2159 0.0381)
							(mid 0 0.254)
							(end 0.2159 0.0381)
						)
					)
					(width 0)
					(fill yes)
				)
			)
		)
		(pad "BA4" smd circle
			(at -34.675064 -5.291074)
			(size 0.4318 0.4318)
			(layers "F.Cu" "F.Mask" "F.Paste")
			(net "UPI_CPU0_CPU1_P0P0_DN<3>")
		)
		(pad "BA6" smd circle
			(at -32.958024 -5.291074)
			(size 0.4318 0.4318)
			(layers "F.Cu" "F.Mask" "F.Paste")
			(net "GND")
		)
		(pad "BA8" smd circle
			(at -31.240984 -5.291074)
			(size 0.4318 0.4318)
			(layers "F.Cu" "F.Mask" "F.Paste")
			(net "UPI_CPU1_CPU0_P0P0_DN<6>")
		)
		(pad "BA10" smd circle
			(at -29.523944 -5.291074)
			(size 0.4318 0.4318)
			(layers "F.Cu" "F.Mask" "F.Paste")
			(net "UPI_CPU1_CPU0_P0P0_DP<0>")
		)
		(pad "BA12" smd circle
			(at -27.806904 -5.291074)
			(size 0.4318 0.4318)
			(layers "F.Cu" "F.Mask" "F.Paste")
			(net "GND")
		)
		(pad "BA14" smd circle
			(at -26.090118 -5.291074)
			(size 0.4318 0.4318)
			(layers "F.Cu" "F.Mask" "F.Paste")
			(net "TP_CPU0_RSVD_178")
		)
		(pad "BA16" smd circle
			(at -24.373078 -5.291074)
			(size 0.4318 0.4318)
			(layers "F.Cu" "F.Mask" "F.Paste")
			(net "TP_CPU0_RSVD_177")
		)
		(pad "BA18" smd circle
			(at -22.656038 -5.291074)
			(size 0.4318 0.4318)
			(layers "F.Cu" "F.Mask" "F.Paste")
			(net "TP_CPU0_RSVD_176")
		)
		(pad "BA20" smd circle
			(at -20.938998 -5.291074)
			(size 0.4318 0.4318)
			(layers "F.Cu" "F.Mask" "F.Paste")
			(net "PD_CPU0_BIST_ENABLE")
		)
		(pad "BA22" smd circle
			(at -19.221958 -5.291074)
			(size 0.4318 0.4318)
			(layers "F.Cu" "F.Mask" "F.Paste")
			(net "TP_CPU0_RSVD_175")
		)
		(pad "BA24" smd circle
			(at -17.504918 -5.291074)
			(size 0.4318 0.4318)
			(layers "F.Cu" "F.Mask" "F.Paste")
			(net "PVCCIO_CPU0")
		)
		(pad "BA26" smd circle
			(at -15.787878 -5.291074)
			(size 0.4318 0.4318)
			(layers "F.Cu" "F.Mask" "F.Paste")
			(net "PVCCIO_CPU0")
		)
		(pad "BA60" smd circle
			(at 14.929612 -7.091172)
			(size 0.508 0.508)
			(layers "F.Cu" "F.Mask" "F.Paste")
			(net "PVCCIN_CPU0")
		)
		(pad "BA62" smd circle
			(at 16.646398 -7.091172)
			(size 0.4318 0.4318)
			(layers "F.Cu" "F.Mask" "F.Paste")
			(net "GND")
		)
		(pad "BA64" smd circle
			(at 18.363438 -7.091172)
			(size 0.4318 0.4318)
			(layers "F.Cu" "F.Mask" "F.Paste")
			(net "TP_CPU0_RSVD_174")
		)
		(pad "BA66" smd circle
			(at 20.080478 -7.091172)
			(size 0.4318 0.4318)
			(layers "F.Cu" "F.Mask" "F.Paste")
			(net "TP_CPU0_RSVD_173")
		)
		(pad "BA68" smd circle
			(at 21.797518 -7.091172)
			(size 0.4318 0.4318)
			(layers "F.Cu" "F.Mask" "F.Paste")
			(net "GND")
		)
		(pad "BA70" smd circle
			(at 23.514558 -7.091172)
			(size 0.4318 0.4318)
			(layers "F.Cu" "F.Mask" "F.Paste")
			(net "M_C_ECC<7>")
		)
		(pad "BA72" smd circle
			(at 25.231598 -7.091172)
			(size 0.4318 0.4318)
			(layers "F.Cu" "F.Mask" "F.Paste")
			(net "M_C_ECC<1>")
		)
		(pad "BA74" smd circle
			(at 26.948384 -7.091172)
			(size 0.4318 0.4318)
			(layers "F.Cu" "F.Mask" "F.Paste")
			(net "GND")
		)
		(pad "BA76" smd circle
			(at 28.665424 -7.091172)
			(size 0.4318 0.4318)
			(layers "F.Cu" "F.Mask" "F.Paste")
			(net "TP_CPU0_RSVD_172")
		)
		(pad "BA78" smd circle
			(at 30.382464 -7.091172)
			(size 0.4318 0.4318)
			(layers "F.Cu" "F.Mask" "F.Paste")
			(net "TP_CPU0_RSVD_171")
		)
		(pad "BA80" smd circle
			(at 32.099504 -7.091172)
			(size 0.4318 0.4318)
			(layers "F.Cu" "F.Mask" "F.Paste")
			(net "GND")
		)
		(pad "BA82" smd circle
			(at 33.816544 -7.091172)
			(size 0.4318 0.4318)
			(layers "F.Cu" "F.Mask" "F.Paste")
			(net "TP_CPU0_RSVD_170")
		)
		(pad "BA84" smd circle
			(at 35.533584 -7.091172)
			(size 0.4318 0.4318)
			(layers "F.Cu" "F.Mask" "F.Paste")
			(net "GND")
		)
		(pad "BA86" smd custom
			(at 37.250624 -7.091172 270)
			(size 0.10795 0.10795)
			(layers "F.Cu" "F.Mask" "F.Paste")
			(net "VSENSE_PVCCIN_CPU0_SKT_VSEN")
			(options
				(clearance outline)
				(anchor circle)
			)
			(primitives
				(gr_poly
					(pts
						(arc
							(start 0.2159 -0.0381)
							(mid 0 -0.254)
							(end -0.2159 -0.0381)
						)
						(arc
							(start -0.2159 0.0381)
							(mid 0 0.254)
							(end 0.2159 0.0381)
						)
					)
					(width 0)
					(fill yes)
				)
			)
		)
		(pad "BB3" smd circle
			(at -35.533584 -4.796028)
			(size 0.4318 0.4318)
			(layers "F.Cu" "F.Mask" "F.Paste")
			(net "UPI_CPU0_CPU1_P0P0_DN<2>")
		)
		(pad "BB5" smd circle
			(at -33.816544 -4.796028)
			(size 0.4318 0.4318)
			(layers "F.Cu" "F.Mask" "F.Paste")
			(net "PVCCIO_CPU0")
		)
		(pad "BB7" smd circle
			(at -32.099504 -4.796028)
			(size 0.4318 0.4318)
			(layers "F.Cu" "F.Mask" "F.Paste")
			(net "UPI_CPU1_CPU0_P0P0_DP<5>")
		)
		(pad "BB9" smd circle
			(at -30.382464 -4.796028)
			(size 0.4318 0.4318)
			(layers "F.Cu" "F.Mask" "F.Paste")
			(net "UPI_CPU1_CPU0_P0P0_DP<2>")
		)
		(pad "BB11" smd circle
			(at -28.665424 -4.796028)
			(size 0.4318 0.4318)
			(layers "F.Cu" "F.Mask" "F.Paste")
			(net "UPI_CPU1_CPU0_P0P0_DN<0>")
		)
		(pad "BB13" smd circle
			(at -26.948384 -4.796028)
			(size 0.4318 0.4318)
			(layers "F.Cu" "F.Mask" "F.Paste")
			(net "TP_CPU0_RSVD_169")
		)
		(pad "BB15" smd circle
			(at -25.231598 -4.796028)
			(size 0.4318 0.4318)
			(layers "F.Cu" "F.Mask" "F.Paste")
			(net "TP_CPU0_RSVD_168")
		)
		(pad "BB17" smd circle
			(at -23.514558 -4.796028)
			(size 0.4318 0.4318)
			(layers "F.Cu" "F.Mask" "F.Paste")
			(net "TP_CPU0_RSVD_167")
		)
		(pad "BB19" smd circle
			(at -21.797518 -4.796028)
			(size 0.4318 0.4318)
			(layers "F.Cu" "F.Mask" "F.Paste")
			(net "GND")
		)
		(pad "BB21" smd circle
			(at -20.080478 -4.796028)
			(size 0.4318 0.4318)
			(layers "F.Cu" "F.Mask" "F.Paste")
			(net "TP_CPU0_RSVD_166")
		)
		(pad "BB23" smd circle
			(at -18.363438 -4.796028)
			(size 0.4318 0.4318)
			(layers "F.Cu" "F.Mask" "F.Paste")
			(net "GND")
		)
		(pad "BB25" smd circle
			(at -16.646398 -4.796028)
			(size 0.4318 0.4318)
			(layers "F.Cu" "F.Mask" "F.Paste")
			(net "CLK_100M_CPU0_RC_REFCLK1_DN")
		)
		(pad "BB27" smd circle
			(at -14.929612 -4.796028)
			(size 0.4318 0.4318)
			(layers "F.Cu" "F.Mask" "F.Paste")
			(net "PVCCIO_CPU0")
		)
		(pad "BB61" smd circle
			(at 15.787878 -6.596126)
			(size 0.4318 0.4318)
			(layers "F.Cu" "F.Mask" "F.Paste")
			(net "PVCCIN_CPU0")
		)
		(pad "BB63" smd circle
			(at 17.504918 -6.596126)
			(size 0.4318 0.4318)
			(layers "F.Cu" "F.Mask" "F.Paste")
			(net "GND")
		)
		(pad "BB65" smd circle
			(at 19.221958 -6.596126)
			(size 0.4318 0.4318)
			(layers "F.Cu" "F.Mask" "F.Paste")
			(net "TP_CPU0_RSVD_164")
		)
		(pad "BB67" smd circle
			(at 20.938998 -6.596126)
			(size 0.4318 0.4318)
			(layers "F.Cu" "F.Mask" "F.Paste")
			(net "TP_CPU0_RSVD_163")
		)
		(pad "BB69" smd circle
			(at 22.656038 -6.596126)
			(size 0.4318 0.4318)
			(layers "F.Cu" "F.Mask" "F.Paste")
			(net "GND")
		)
		(pad "BB71" smd circle
			(at 24.373078 -6.596126)
			(size 0.4318 0.4318)
			(layers "F.Cu" "F.Mask" "F.Paste")
			(net "M_C_DQS_DN<8>")
		)
		(pad "BB73" smd circle
			(at 26.090118 -6.596126)
			(size 0.4318 0.4318)
			(layers "F.Cu" "F.Mask" "F.Paste")
			(net "GND")
		)
		(pad "BB75" smd circle
			(at 27.806904 -6.596126)
			(size 0.4318 0.4318)
			(layers "F.Cu" "F.Mask" "F.Paste")
			(net "GND")
		)
		(pad "BB77" smd circle
			(at 29.523944 -6.596126)
			(size 0.4318 0.4318)
			(layers "F.Cu" "F.Mask" "F.Paste")
			(net "GND")
		)
	)
)
